(kicad_pcb
	(version 20260206)
	(generator "pcbnew")
	(generator_version "10.0")
	(general
		(thickness 1.6)
		(legacy_teardrops no)
	)
	(paper "A4")
	(title_block
		(title "03242023_DA0F0TMBIJ0_F0T_Motherboard_J_brd_V01_OCP.brd")
		(comment 1 "Grand Teton / footprint 1301 of 6105 (J27), pads 1-112 of 291")
	)
	(layers
		(0 "F.Cu" signal "TOP")
		(4 "In1.Cu" signal "GND")
		(6 "In2.Cu" signal "IN1")
		(8 "In3.Cu" signal "GND1")
		(10 "In4.Cu" signal "IN2")
		(12 "In5.Cu" signal "GND2")
		(14 "In6.Cu" signal "IN3")
		(16 "In7.Cu" signal "GND3")
		(18 "In8.Cu" signal "VCC")
		(20 "In9.Cu" signal "VCC1")
		(22 "In10.Cu" signal "GND4")
		(24 "In11.Cu" signal "IN4")
		(26 "In12.Cu" signal "GND5")
		(28 "In13.Cu" signal "IN5")
		(30 "In14.Cu" signal "GND6")
		(32 "In15.Cu" signal "IN6")
		(34 "In16.Cu" signal "GND7")
		(2 "B.Cu" signal "BOTTOM")
		(9 "F.Adhes" user "F.Adhesive")
		(11 "B.Adhes" user "B.Adhesive")
		(13 "F.Paste" user "Package Geometry/Pastemask Top")
		(15 "B.Paste" user "Package Geometry/Pastemask Bottom")
		(5 "F.SilkS" user "Ref Des/Silkscreen Top")
		(7 "B.SilkS" user "Ref Des/Silkscreen Bottom")
		(1 "F.Mask" user "Board Geometry/Soldermask Top")
		(3 "B.Mask" user "Board Geometry/Soldermask Bottom")
		(17 "Dwgs.User" user "User.Drawings")
		(19 "Cmts.User" user "User.Comments")
		(21 "Eco1.User" user "User.Eco1")
		(23 "Eco2.User" user "User.Eco2")
		(25 "Edge.Cuts" user "Board Geometry/Outline")
		(27 "Margin" user)
		(31 "F.CrtYd" user "Package Geometry/Place Bound Top")
		(29 "B.CrtYd" user "Package Geometry/Place Bound Bottom")
		(35 "F.Fab" user "Ref Des/Assembly Top")
		(33 "B.Fab" user "Ref Des/Assembly Bottom")
	)
	(footprint ""
		(layer "F.Cu")
		(at 183.49468 -258.091686)
		(property "Reference" "J27"
			(at 2.19456 -81.755488 0)
			(unlocked yes)
			(layer "F.SilkS")
			(effects
				(font
					(size 0.7874 0.5842)
					(thickness 0.1524)
				)
				(justify left)
			)
		)
		(property "Value" ""
			(at 0 0 0)
			(layer "F.Fab")
			(effects
				(font
					(size 1.27 1.27)
				)
			)
		)
		(duplicate_pad_numbers_are_jumpers no)
		(pad "1" smd rect
			(at -2.050034 -63.324994 270)
			(size 0.519938 1.4986)
			(layers "F.Cu" "F.Mask" "F.Paste")
			(net "P12V_S3_AUX_CPU1_NVDIMM")
		)
		(pad "2" smd rect
			(at -2.050034 -62.47511 270)
			(size 0.519938 1.4986)
			(layers "F.Cu" "F.Mask" "F.Paste")
			(net "TP_CHF_CPU1_DIMM1_FRU_0")
		)
		(pad "3" smd rect
			(at -2.050034 -61.624972 270)
			(size 0.519938 1.4986)
			(layers "F.Cu" "F.Mask" "F.Paste")
			(net "P3V3_AUX")
		)
		(pad "4" smd rect
			(at -2.050034 -60.775088 270)
			(size 0.519938 1.4986)
			(layers "F.Cu" "F.Mask" "F.Paste")
			(net "I3C_SPD_DDREFGH_CPU1_LVC1_SCL_2")
		)
		(pad "5" smd rect
			(at -2.050034 -59.92495 270)
			(size 0.519938 1.4986)
			(layers "F.Cu" "F.Mask" "F.Paste")
			(net "I3C_SPD_DDREFGH_CPU1_LVC1_SDA")
		)
		(pad "6" smd rect
			(at -2.050034 -59.075066 270)
			(size 0.519938 1.4986)
			(layers "F.Cu" "F.Mask" "F.Paste")
			(net "GND")
		)
		(pad "7" smd rect
			(at -2.050034 -58.224928 270)
			(size 0.519938 1.4986)
			(layers "F.Cu" "F.Mask" "F.Paste")
			(net "M_F_CPU1_SA_DQ<0>")
		)
		(pad "8" smd rect
			(at -2.050034 -57.375044 270)
			(size 0.519938 1.4986)
			(layers "F.Cu" "F.Mask" "F.Paste")
			(net "GND")
		)
		(pad "9" smd rect
			(at -2.050034 -56.524906 270)
			(size 0.519938 1.4986)
			(layers "F.Cu" "F.Mask" "F.Paste")
			(net "M_F_CPU1_SA_DQ<1>")
		)
		(pad "10" smd rect
			(at -2.050034 -55.675022 270)
			(size 0.519938 1.4986)
			(layers "F.Cu" "F.Mask" "F.Paste")
			(net "GND")
		)
		(pad "11" smd rect
			(at -2.050034 -54.824884 270)
			(size 0.519938 1.4986)
			(layers "F.Cu" "F.Mask" "F.Paste")
			(net "M_F_CPU1_SA_DQS_DP<0>")
		)
		(pad "12" smd rect
			(at -2.050034 -53.975 270)
			(size 0.519938 1.4986)
			(layers "F.Cu" "F.Mask" "F.Paste")
			(net "M_F_CPU1_SA_DQS_DN<0>")
		)
		(pad "13" smd rect
			(at -2.050034 -53.125116 270)
			(size 0.519938 1.4986)
			(layers "F.Cu" "F.Mask" "F.Paste")
			(net "GND")
		)
		(pad "14" smd rect
			(at -2.050034 -52.274978 270)
			(size 0.519938 1.4986)
			(layers "F.Cu" "F.Mask" "F.Paste")
			(net "M_F_CPU1_SA_DQ<4>")
		)
		(pad "15" smd rect
			(at -2.050034 -51.425094 270)
			(size 0.519938 1.4986)
			(layers "F.Cu" "F.Mask" "F.Paste")
			(net "GND")
		)
		(pad "16" smd rect
			(at -2.050034 -50.574956 270)
			(size 0.519938 1.4986)
			(layers "F.Cu" "F.Mask" "F.Paste")
			(net "M_F_CPU1_SA_DQ<5>")
		)
		(pad "17" smd rect
			(at -2.050034 -49.725072 270)
			(size 0.519938 1.4986)
			(layers "F.Cu" "F.Mask" "F.Paste")
			(net "GND")
		)
		(pad "18" smd rect
			(at -2.050034 -48.874934 270)
			(size 0.519938 1.4986)
			(layers "F.Cu" "F.Mask" "F.Paste")
			(net "M_F_CPU1_SA_DQ<8>")
		)
		(pad "19" smd rect
			(at -2.050034 -48.02505 270)
			(size 0.519938 1.4986)
			(layers "F.Cu" "F.Mask" "F.Paste")
			(net "GND")
		)
		(pad "20" smd rect
			(at -2.050034 -47.174912 270)
			(size 0.519938 1.4986)
			(layers "F.Cu" "F.Mask" "F.Paste")
			(net "M_F_CPU1_SA_DQ<9>")
		)
		(pad "21" smd rect
			(at -2.050034 -46.325028 270)
			(size 0.519938 1.4986)
			(layers "F.Cu" "F.Mask" "F.Paste")
			(net "GND")
		)
		(pad "22" smd rect
			(at -2.050034 -45.47489 270)
			(size 0.519938 1.4986)
			(layers "F.Cu" "F.Mask" "F.Paste")
			(net "M_F_CPU1_SA_DQS_DP<1>")
		)
		(pad "23" smd rect
			(at -2.050034 -44.625006 270)
			(size 0.519938 1.4986)
			(layers "F.Cu" "F.Mask" "F.Paste")
			(net "M_F_CPU1_SA_DQS_DN<1>")
		)
		(pad "24" smd rect
			(at -2.050034 -43.775122 270)
			(size 0.519938 1.4986)
			(layers "F.Cu" "F.Mask" "F.Paste")
			(net "GND")
		)
		(pad "25" smd rect
			(at -2.050034 -42.924984 270)
			(size 0.519938 1.4986)
			(layers "F.Cu" "F.Mask" "F.Paste")
			(net "M_F_CPU1_SA_DQ<12>")
		)
		(pad "26" smd rect
			(at -2.050034 -42.0751 270)
			(size 0.519938 1.4986)
			(layers "F.Cu" "F.Mask" "F.Paste")
			(net "GND")
		)
		(pad "27" smd rect
			(at -2.050034 -41.224962 270)
			(size 0.519938 1.4986)
			(layers "F.Cu" "F.Mask" "F.Paste")
			(net "M_F_CPU1_SA_DQ<13>")
		)
		(pad "28" smd rect
			(at -2.050034 -40.375078 270)
			(size 0.519938 1.4986)
			(layers "F.Cu" "F.Mask" "F.Paste")
			(net "GND")
		)
		(pad "29" smd rect
			(at -2.050034 -39.52494 270)
			(size 0.519938 1.4986)
			(layers "F.Cu" "F.Mask" "F.Paste")
			(net "M_F_CPU1_SA_DQ<16>")
		)
		(pad "30" smd rect
			(at -2.050034 -38.675056 270)
			(size 0.519938 1.4986)
			(layers "F.Cu" "F.Mask" "F.Paste")
			(net "GND")
		)
		(pad "31" smd rect
			(at -2.050034 -37.824918 270)
			(size 0.519938 1.4986)
			(layers "F.Cu" "F.Mask" "F.Paste")
			(net "M_F_CPU1_SA_DQ<17>")
		)
		(pad "32" smd rect
			(at -2.050034 -36.975034 270)
			(size 0.519938 1.4986)
			(layers "F.Cu" "F.Mask" "F.Paste")
			(net "GND")
		)
		(pad "33" smd rect
			(at -2.050034 -36.124896 270)
			(size 0.519938 1.4986)
			(layers "F.Cu" "F.Mask" "F.Paste")
			(net "M_F_CPU1_SA_DQS_DP<2>")
		)
		(pad "34" smd rect
			(at -2.050034 -35.275012 270)
			(size 0.519938 1.4986)
			(layers "F.Cu" "F.Mask" "F.Paste")
			(net "M_F_CPU1_SA_DQS_DN<2>")
		)
		(pad "35" smd rect
			(at -2.050034 -34.425128 270)
			(size 0.519938 1.4986)
			(layers "F.Cu" "F.Mask" "F.Paste")
			(net "GND")
		)
		(pad "36" smd rect
			(at -2.050034 -33.57499 270)
			(size 0.519938 1.4986)
			(layers "F.Cu" "F.Mask" "F.Paste")
			(net "M_F_CPU1_SA_DQ<20>")
		)
		(pad "37" smd rect
			(at -2.050034 -32.725106 270)
			(size 0.519938 1.4986)
			(layers "F.Cu" "F.Mask" "F.Paste")
			(net "GND")
		)
		(pad "38" smd rect
			(at -2.050034 -31.874968 270)
			(size 0.519938 1.4986)
			(layers "F.Cu" "F.Mask" "F.Paste")
			(net "M_F_CPU1_SA_DQ<21>")
		)
		(pad "39" smd rect
			(at -2.050034 -31.025084 270)
			(size 0.519938 1.4986)
			(layers "F.Cu" "F.Mask" "F.Paste")
			(net "GND")
		)
		(pad "40" smd rect
			(at -2.050034 -30.174946 270)
			(size 0.519938 1.4986)
			(layers "F.Cu" "F.Mask" "F.Paste")
			(net "M_F_CPU1_SA_DQ<24>")
		)
		(pad "41" smd rect
			(at -2.050034 -29.325062 270)
			(size 0.519938 1.4986)
			(layers "F.Cu" "F.Mask" "F.Paste")
			(net "GND")
		)
		(pad "42" smd rect
			(at -2.050034 -28.474924 270)
			(size 0.519938 1.4986)
			(layers "F.Cu" "F.Mask" "F.Paste")
			(net "M_F_CPU1_SA_DQ<25>")
		)
		(pad "43" smd rect
			(at -2.050034 -27.62504 270)
			(size 0.519938 1.4986)
			(layers "F.Cu" "F.Mask" "F.Paste")
			(net "GND")
		)
		(pad "44" smd rect
			(at -2.050034 -26.774902 270)
			(size 0.519938 1.4986)
			(layers "F.Cu" "F.Mask" "F.Paste")
			(net "M_F_CPU1_SA_DQS_DP<3>")
		)
		(pad "45" smd rect
			(at -2.050034 -25.925018 270)
			(size 0.519938 1.4986)
			(layers "F.Cu" "F.Mask" "F.Paste")
			(net "M_F_CPU1_SA_DQS_DN<3>")
		)
		(pad "46" smd rect
			(at -2.050034 -25.07488 270)
			(size 0.519938 1.4986)
			(layers "F.Cu" "F.Mask" "F.Paste")
			(net "GND")
		)
		(pad "47" smd rect
			(at -2.050034 -24.224996 270)
			(size 0.519938 1.4986)
			(layers "F.Cu" "F.Mask" "F.Paste")
			(net "M_F_CPU1_SA_DQ<28>")
		)
		(pad "48" smd rect
			(at -2.050034 -23.375112 270)
			(size 0.519938 1.4986)
			(layers "F.Cu" "F.Mask" "F.Paste")
			(net "GND")
		)
		(pad "49" smd rect
			(at -2.050034 -22.524974 270)
			(size 0.519938 1.4986)
			(layers "F.Cu" "F.Mask" "F.Paste")
			(net "M_F_CPU1_SA_DQ<29>")
		)
		(pad "50" smd rect
			(at -2.050034 -21.67509 270)
			(size 0.519938 1.4986)
			(layers "F.Cu" "F.Mask" "F.Paste")
			(net "GND")
		)
		(pad "51" smd rect
			(at -2.050034 -20.824952 270)
			(size 0.519938 1.4986)
			(layers "F.Cu" "F.Mask" "F.Paste")
			(net "M_F_CPU1_SA_CB<0>")
		)
		(pad "52" smd rect
			(at -2.050034 -19.975068 270)
			(size 0.519938 1.4986)
			(layers "F.Cu" "F.Mask" "F.Paste")
			(net "GND")
		)
		(pad "53" smd rect
			(at -2.050034 -19.12493 270)
			(size 0.519938 1.4986)
			(layers "F.Cu" "F.Mask" "F.Paste")
			(net "M_F_CPU1_SA_CB<1>")
		)
		(pad "54" smd rect
			(at -2.050034 -18.275046 270)
			(size 0.519938 1.4986)
			(layers "F.Cu" "F.Mask" "F.Paste")
			(net "GND")
		)
		(pad "55" smd rect
			(at -2.050034 -17.424908 270)
			(size 0.519938 1.4986)
			(layers "F.Cu" "F.Mask" "F.Paste")
			(net "M_F_CPU1_SA_DQS_DP<4>")
		)
		(pad "56" smd rect
			(at -2.050034 -16.575024 270)
			(size 0.519938 1.4986)
			(layers "F.Cu" "F.Mask" "F.Paste")
			(net "M_F_CPU1_SA_DQS_DN<4>")
		)
		(pad "57" smd rect
			(at -2.050034 -15.724886 270)
			(size 0.519938 1.4986)
			(layers "F.Cu" "F.Mask" "F.Paste")
			(net "GND")
		)
		(pad "58" smd rect
			(at -2.050034 -14.875002 270)
			(size 0.519938 1.4986)
			(layers "F.Cu" "F.Mask" "F.Paste")
			(net "M_F_CPU1_SA_CB<4>")
		)
		(pad "59" smd rect
			(at -2.050034 -14.025118 270)
			(size 0.519938 1.4986)
			(layers "F.Cu" "F.Mask" "F.Paste")
			(net "GND")
		)
		(pad "60" smd rect
			(at -2.050034 -13.17498 270)
			(size 0.519938 1.4986)
			(layers "F.Cu" "F.Mask" "F.Paste")
			(net "M_F_CPU1_SA_CB<5>")
		)
		(pad "61" smd rect
			(at -2.050034 -12.325096 270)
			(size 0.519938 1.4986)
			(layers "F.Cu" "F.Mask" "F.Paste")
			(net "GND")
		)
		(pad "62" smd rect
			(at -2.050034 -11.474958 270)
			(size 0.519938 1.4986)
			(layers "F.Cu" "F.Mask" "F.Paste")
			(net "M_F_CPU1_ALERT_N")
		)
		(pad "63" smd rect
			(at -2.050034 -10.625074 270)
			(size 0.519938 1.4986)
			(layers "F.Cu" "F.Mask" "F.Paste")
			(net "GND")
		)
		(pad "64" smd rect
			(at -2.050034 -9.774936 270)
			(size 0.519938 1.4986)
			(layers "F.Cu" "F.Mask" "F.Paste")
			(net "M_F_CPU1_SA_CS_N<0>")
		)
		(pad "65" smd rect
			(at -2.050034 -8.925052 270)
			(size 0.519938 1.4986)
			(layers "F.Cu" "F.Mask" "F.Paste")
			(net "GND")
		)
		(pad "66" smd rect
			(at -2.050034 -8.074914 270)
			(size 0.519938 1.4986)
			(layers "F.Cu" "F.Mask" "F.Paste")
			(net "M_F_CPU1_SA_CA<0>")
		)
		(pad "67" smd rect
			(at -2.050034 -7.22503 270)
			(size 0.519938 1.4986)
			(layers "F.Cu" "F.Mask" "F.Paste")
			(net "GND")
		)
		(pad "68" smd rect
			(at -2.050034 -6.374892 270)
			(size 0.519938 1.4986)
			(layers "F.Cu" "F.Mask" "F.Paste")
			(net "M_F_CPU1_SA_CA<2>")
		)
		(pad "69" smd rect
			(at -2.050034 -5.525008 270)
			(size 0.519938 1.4986)
			(layers "F.Cu" "F.Mask" "F.Paste")
			(net "GND")
		)
		(pad "70" smd rect
			(at -2.050034 -4.675124 270)
			(size 0.519938 1.4986)
			(layers "F.Cu" "F.Mask" "F.Paste")
			(net "M_F_CPU1_SA_CA<4>")
		)
		(pad "71" smd rect
			(at -2.050034 -3.824986 270)
			(size 0.519938 1.4986)
			(layers "F.Cu" "F.Mask" "F.Paste")
			(net "GND")
		)
		(pad "72" smd rect
			(at -2.050034 -2.975102 270)
			(size 0.519938 1.4986)
			(layers "F.Cu" "F.Mask" "F.Paste")
			(net "M_F_CPU1_SA_CA<6>")
		)
		(pad "73" smd rect
			(at -2.050034 -2.124964 270)
			(size 0.519938 1.4986)
			(layers "F.Cu" "F.Mask" "F.Paste")
			(net "GND")
		)
		(pad "74" smd rect
			(at -2.050034 -1.27508 270)
			(size 0.519938 1.4986)
			(layers "F.Cu" "F.Mask" "F.Paste")
			(net "M_F_CPU1_SA_PAR")
		)
		(pad "75" smd rect
			(at -2.050034 -0.424942 270)
			(size 0.519938 1.4986)
			(layers "F.Cu" "F.Mask" "F.Paste")
			(net "GND")
		)
		(pad "76" smd rect
			(at -2.050034 5.525008 270)
			(size 0.519938 1.4986)
			(layers "F.Cu" "F.Mask" "F.Paste")
			(net "M_F_CPU1_SB_CA<0>")
		)
		(pad "77" smd rect
			(at -2.050034 6.374892 270)
			(size 0.519938 1.4986)
			(layers "F.Cu" "F.Mask" "F.Paste")
			(net "GND")
		)
		(pad "78" smd rect
			(at -2.050034 7.22503 270)
			(size 0.519938 1.4986)
			(layers "F.Cu" "F.Mask" "F.Paste")
			(net "M_F_CPU1_SB_CA<2>")
		)
		(pad "79" smd rect
			(at -2.050034 8.074914 270)
			(size 0.519938 1.4986)
			(layers "F.Cu" "F.Mask" "F.Paste")
			(net "GND")
		)
		(pad "80" smd rect
			(at -2.050034 8.925052 270)
			(size 0.519938 1.4986)
			(layers "F.Cu" "F.Mask" "F.Paste")
			(net "M_F_CPU1_SB_CA<4>")
		)
		(pad "81" smd rect
			(at -2.050034 9.774936 270)
			(size 0.519938 1.4986)
			(layers "F.Cu" "F.Mask" "F.Paste")
			(net "GND")
		)
		(pad "82" smd rect
			(at -2.050034 10.625074 270)
			(size 0.519938 1.4986)
			(layers "F.Cu" "F.Mask" "F.Paste")
			(net "M_F_CPU1_SB_CA<6>")
		)
		(pad "83" smd rect
			(at -2.050034 11.474958 270)
			(size 0.519938 1.4986)
			(layers "F.Cu" "F.Mask" "F.Paste")
			(net "GND")
		)
		(pad "84" smd rect
			(at -2.050034 12.325096 270)
			(size 0.519938 1.4986)
			(layers "F.Cu" "F.Mask" "F.Paste")
			(net "M_F_CPU1_SB_CS_N<0>")
		)
		(pad "85" smd rect
			(at -2.050034 13.17498 270)
			(size 0.519938 1.4986)
			(layers "F.Cu" "F.Mask" "F.Paste")
			(net "GND")
		)
		(pad "86" smd rect
			(at -2.050034 14.025118 270)
			(size 0.519938 1.4986)
			(layers "F.Cu" "F.Mask" "F.Paste")
			(net "M_F_CPU1_SA_RSP<0>")
		)
		(pad "87" smd rect
			(at -2.050034 14.875002 270)
			(size 0.519938 1.4986)
			(layers "F.Cu" "F.Mask" "F.Paste")
			(net "M_F_CPU1_SB_RSP<0>")
		)
		(pad "88" smd rect
			(at -2.050034 15.724886 270)
			(size 0.519938 1.4986)
			(layers "F.Cu" "F.Mask" "F.Paste")
			(net "GND")
		)
		(pad "89" smd rect
			(at -2.050034 16.575024 270)
			(size 0.519938 1.4986)
			(layers "F.Cu" "F.Mask" "F.Paste")
			(net "M_F_CPU1_SB_CB<4>")
		)
		(pad "90" smd rect
			(at -2.050034 17.424908 270)
			(size 0.519938 1.4986)
			(layers "F.Cu" "F.Mask" "F.Paste")
			(net "GND")
		)
		(pad "91" smd rect
			(at -2.050034 18.275046 270)
			(size 0.519938 1.4986)
			(layers "F.Cu" "F.Mask" "F.Paste")
			(net "M_F_CPU1_SB_CB<5>")
		)
		(pad "92" smd rect
			(at -2.050034 19.12493 270)
			(size 0.519938 1.4986)
			(layers "F.Cu" "F.Mask" "F.Paste")
			(net "GND")
		)
		(pad "93" smd rect
			(at -2.050034 19.975068 270)
			(size 0.519938 1.4986)
			(layers "F.Cu" "F.Mask" "F.Paste")
			(net "M_F_CPU1_SB_DQS_DP<9>")
		)
		(pad "94" smd rect
			(at -2.050034 20.824952 270)
			(size 0.519938 1.4986)
			(layers "F.Cu" "F.Mask" "F.Paste")
			(net "M_F_CPU1_SB_DQS_DN<9>")
		)
		(pad "95" smd rect
			(at -2.050034 21.67509 270)
			(size 0.519938 1.4986)
			(layers "F.Cu" "F.Mask" "F.Paste")
			(net "GND")
		)
		(pad "96" smd rect
			(at -2.050034 22.524974 270)
			(size 0.519938 1.4986)
			(layers "F.Cu" "F.Mask" "F.Paste")
			(net "M_F_CPU1_SB_CB<0>")
		)
		(pad "97" smd rect
			(at -2.050034 23.375112 270)
			(size 0.519938 1.4986)
			(layers "F.Cu" "F.Mask" "F.Paste")
			(net "GND")
		)
		(pad "98" smd rect
			(at -2.050034 24.224996 270)
			(size 0.519938 1.4986)
			(layers "F.Cu" "F.Mask" "F.Paste")
			(net "M_F_CPU1_SB_CB<1>")
		)
		(pad "99" smd rect
			(at -2.050034 25.07488 270)
			(size 0.519938 1.4986)
			(layers "F.Cu" "F.Mask" "F.Paste")
			(net "GND")
		)
		(pad "100" smd rect
			(at -2.050034 25.925018 270)
			(size 0.519938 1.4986)
			(layers "F.Cu" "F.Mask" "F.Paste")
			(net "M_F_CPU1_SB_DQ<0>")
		)
		(pad "101" smd rect
			(at -2.050034 26.774902 270)
			(size 0.519938 1.4986)
			(layers "F.Cu" "F.Mask" "F.Paste")
			(net "GND")
		)
		(pad "102" smd rect
			(at -2.050034 27.62504 270)
			(size 0.519938 1.4986)
			(layers "F.Cu" "F.Mask" "F.Paste")
			(net "M_F_CPU1_SB_DQ<1>")
		)
		(pad "103" smd rect
			(at -2.050034 28.474924 270)
			(size 0.519938 1.4986)
			(layers "F.Cu" "F.Mask" "F.Paste")
			(net "GND")
		)
		(pad "104" smd rect
			(at -2.050034 29.325062 270)
			(size 0.519938 1.4986)
			(layers "F.Cu" "F.Mask" "F.Paste")
			(net "M_F_CPU1_SB_DQS_DP<0>")
		)
		(pad "105" smd rect
			(at -2.050034 30.174946 270)
			(size 0.519938 1.4986)
			(layers "F.Cu" "F.Mask" "F.Paste")
			(net "M_F_CPU1_SB_DQS_DN<0>")
		)
		(pad "106" smd rect
			(at -2.050034 31.025084 270)
			(size 0.519938 1.4986)
			(layers "F.Cu" "F.Mask" "F.Paste")
			(net "GND")
		)
		(pad "107" smd rect
			(at -2.050034 31.874968 270)
			(size 0.519938 1.4986)
			(layers "F.Cu" "F.Mask" "F.Paste")
			(net "M_F_CPU1_SB_DQ<4>")
		)
		(pad "108" smd rect
			(at -2.050034 32.725106 270)
			(size 0.519938 1.4986)
			(layers "F.Cu" "F.Mask" "F.Paste")
			(net "GND")
		)
		(pad "109" smd rect
			(at -2.050034 33.57499 270)
			(size 0.519938 1.4986)
			(layers "F.Cu" "F.Mask" "F.Paste")
			(net "M_F_CPU1_SB_DQ<5>")
		)
		(pad "110" smd rect
			(at -2.050034 34.425128 270)
			(size 0.519938 1.4986)
			(layers "F.Cu" "F.Mask" "F.Paste")
			(net "GND")
		)
		(pad "111" smd rect
			(at -2.050034 35.275012 270)
			(size 0.519938 1.4986)
			(layers "F.Cu" "F.Mask" "F.Paste")
			(net "M_F_CPU1_SB_DQ<8>")
		)
		(pad "112" smd rect
			(at -2.050034 36.124896 270)
			(size 0.519938 1.4986)
			(layers "F.Cu" "F.Mask" "F.Paste")
			(net "GND")
		)
	)
)
